# BASEBOARD_FAB2 (Tioga Pass) — schematic netlist excerpt (pin names and nets, part order shuffled) for the footprints in the layout excerpt that follows; sources: Cadence DE-HDL packaged netlist, KiCad conversion of Wiwynn_Tioga_Pass_MB.brd

C5D50  CAP_A  22.0UF 4V 20% X6S  pkg 0603V  page 42 : A = PVCCMCP_CPU0 ; B = GND
R4B3  RES  0.0 5% CHIP  pkg 0402  page 234 : A = PVPP_KLM ; B = VSENSE_PVPP_KLM
C4G12  CAP  1000PF 50V 10% EMPTY  pkg 0402LF  page 229 : A = FM_PVTT_GHJ_EN_R ; B = GND

(kicad_pcb
	(version 20260206)
	(generator "pcbnew")
	(generator_version "10.0")
	(general
		(thickness 1.6)
		(legacy_teardrops no)
	)
	(paper "A4")
	(title_block
		(title "Wiwynn_Tioga_Pass_MB.brd")
		(comment 1 "Tioga Pass / footprints 1247-1249 of 4770")
	)
	(layers
		(0 "F.Cu" signal "TOP")
		(4 "In1.Cu" signal "L2GND")
		(6 "In2.Cu" signal "L3")
		(8 "In3.Cu" signal "L4GND")
		(10 "In4.Cu" signal "L5")
		(12 "In5.Cu" signal "L6GND")
		(14 "In6.Cu" signal "L7VCC")
		(16 "In7.Cu" signal "L8VCC")
		(18 "In8.Cu" signal "L9GND")
		(20 "In9.Cu" signal "L10")
		(22 "In10.Cu" signal "L11GND")
		(24 "In11.Cu" signal "L12")
		(26 "In12.Cu" signal "L13GND")
		(2 "B.Cu" signal "BOTTOM")
		(9 "F.Adhes" user "F.Adhesive")
		(11 "B.Adhes" user "B.Adhesive")
		(13 "F.Paste" user "Package Geometry/Pastemask Top")
		(15 "B.Paste" user "Package Geometry/Pastemask Bottom")
		(5 "F.SilkS" user "Ref Des/Silkscreen Top")
		(7 "B.SilkS" user "Ref Des/Silkscreen Bottom")
		(1 "F.Mask" user "Board Geometry/Soldermask Top")
		(3 "B.Mask" user "Board Geometry/Soldermask Bottom")
		(17 "Dwgs.User" user "User.Drawings")
		(19 "Cmts.User" user "User.Comments")
		(21 "Eco1.User" user "User.Eco1")
		(23 "Eco2.User" user "User.Eco2")
		(25 "Edge.Cuts" user "Board Geometry/Outline")
		(27 "Margin" user)
		(31 "F.CrtYd" user "Package Geometry/Place Bound Top")
		(29 "B.CrtYd" user "Package Geometry/Place Bound Bottom")
		(35 "F.Fab" user "Ref Des/Assembly Top")
		(33 "B.Fab" user "Ref Des/Assembly Bottom")
	)
	(footprint ""
		(layer "F.Cu")
		(at 170.0276 -131.8768)
		(property "Reference" "R4B3"
			(at 0 0 0)
			(layer "F.SilkS")
			(hide yes)
			(effects
				(font
					(size 1.27 1.27)
				)
			)
		)
		(property "Value" ""
			(at 0 0 0)
			(layer "F.Fab")
			(effects
				(font
					(size 1.27 1.27)
				)
			)
		)
		(duplicate_pad_numbers_are_jumpers no)
		(fp_poly
			(pts
				(xy -0.2794 -0.1016) (xy 0.2794 -0.1016) (xy 0.2794 0.9906) (xy -0.2794 0.9906)
			)
			(stroke
				(width 0)
				(type default)
			)
			(fill no)
			(layer "F.CrtYd")
		)
		(fp_line
			(start -0.2794 -0.1016)
			(end -0.2794 0.9906)
			(stroke
				(width 0.1)
				(type default)
			)
			(layer "F.Fab")
		)
		(fp_line
			(start -0.2794 0.9906)
			(end 0.2794 0.9906)
			(stroke
				(width 0.1)
				(type default)
			)
			(layer "F.Fab")
		)
		(fp_line
			(start 0.2794 -0.1016)
			(end -0.2794 -0.1016)
			(stroke
				(width 0.1)
				(type default)
			)
			(layer "F.Fab")
		)
		(fp_line
			(start 0.2794 0.9906)
			(end 0.2794 -0.1016)
			(stroke
				(width 0.1)
				(type default)
			)
			(layer "F.Fab")
		)
		(pad "1" smd rect
			(at 0 0)
			(size 0.508 0.508)
			(layers "F.Cu" "F.Mask" "F.Paste")
			(net "PVPP_KLM")
		)
		(pad "2" smd rect
			(at 0 0.889)
			(size 0.508 0.508)
			(layers "F.Cu" "F.Mask" "F.Paste")
			(net "VSENSE_PVPP_KLM")
		)
		(zone
			(layer "F.Cu")
			(hatch none 0.5)
			(connect_pads
				(clearance 0)
			)
			(min_thickness 0.25)
			(keepout
				(tracks allowed)
				(vias not_allowed)
				(pads allowed)
				(copperpour not_allowed)
				(footprints allowed)
			)
			(placement
				(enabled no)
				(sheetname "")
			)
			(fill
				(thermal_gap 0.5)
				(thermal_bridge_width 0.5)
				(island_removal_mode 0)
			)
			(polygon
				(pts
					(xy 169.7736 -131.6228) (xy 170.2816 -131.6228) (xy 170.2816 -131.2418) (xy 169.7736 -131.2418)
				)
			)
		)
		(zone
			(layer "F.Cu")
			(hatch none 0.5)
			(connect_pads
				(clearance 0)
			)
			(min_thickness 0.25)
			(keepout
				(tracks not_allowed)
				(vias allowed)
				(pads allowed)
				(copperpour not_allowed)
				(footprints allowed)
			)
			(placement
				(enabled no)
				(sheetname "")
			)
			(fill
				(thermal_gap 0.5)
				(thermal_bridge_width 0.5)
				(island_removal_mode 0)
			)
			(polygon
				(pts
					(xy 169.7736 -131.2418) (xy 170.2816 -131.2418) (xy 170.2816 -131.6228) (xy 169.7736 -131.6228)
				)
			)
		)
	)
	(footprint ""
		(layer "F.Cu")
		(at 275.708872 -73.318116)
		(property "Reference" "C5D50"
			(at 0 0 0)
			(layer "F.SilkS")
			(hide yes)
			(effects
				(font
					(size 1.27 1.27)
				)
			)
		)
		(property "Value" ""
			(at 0 0 0)
			(layer "F.Fab")
			(effects
				(font
					(size 1.27 1.27)
				)
			)
		)
		(duplicate_pad_numbers_are_jumpers no)
		(fp_poly
			(pts
				(xy -0.4953 -0.2032) (xy 0.4953 -0.2032) (xy 0.4953 1.6002) (xy -0.4953 1.6002)
			)
			(stroke
				(width 0)
				(type default)
			)
			(fill no)
			(layer "F.CrtYd")
		)
		(fp_line
			(start -0.4953 -0.2032)
			(end 0.4953 -0.2032)
			(stroke
				(width 0.1)
				(type default)
			)
			(layer "F.Fab")
		)
		(fp_line
			(start -0.4953 1.6002)
			(end -0.4953 -0.2032)
			(stroke
				(width 0.1)
				(type default)
			)
			(layer "F.Fab")
		)
		(fp_line
			(start 0.4953 -0.2032)
			(end 0.4953 1.6002)
			(stroke
				(width 0.1)
				(type default)
			)
			(layer "F.Fab")
		)
		(fp_line
			(start 0.4953 1.6002)
			(end -0.4953 1.6002)
			(stroke
				(width 0.1)
				(type default)
			)
			(layer "F.Fab")
		)
		(pad "1" smd rect
			(at 0 0)
			(size 0.762 0.889)
			(layers "F.Cu" "F.Mask" "F.Paste")
			(net "PVCCMCP_CPU0")
		)
		(pad "2" smd rect
			(at 0 1.397)
			(size 0.762 0.889)
			(layers "F.Cu" "F.Mask" "F.Paste")
			(net "GND")
		)
		(zone
			(layer "F.Cu")
			(hatch none 0.5)
			(connect_pads
				(clearance 0)
			)
			(min_thickness 0.25)
			(keepout
				(tracks not_allowed)
				(vias allowed)
				(pads allowed)
				(copperpour not_allowed)
				(footprints allowed)
			)
			(placement
				(enabled no)
				(sheetname "")
			)
			(fill
				(thermal_gap 0.5)
				(thermal_bridge_width 0.5)
				(island_removal_mode 0)
			)
			(polygon
				(pts
					(xy 275.327872 -72.873616) (xy 276.089872 -72.873616) (xy 276.089872 -72.365616) (xy 275.327872 -72.365616)
				)
			)
		)
	)
	(footprint ""
		(layer "F.Cu")
		(at 167.3098 -6.5024 180)
		(property "Reference" "C4G12"
			(at 0 0 180)
			(layer "F.SilkS")
			(hide yes)
			(effects
				(font
					(size 1.27 1.27)
				)
			)
		)
		(property "Value" ""
			(at 0 0 180)
			(layer "F.Fab")
			(effects
				(font
					(size 1.27 1.27)
				)
			)
		)
		(duplicate_pad_numbers_are_jumpers no)
		(fp_rect
			(start -0.3048 -0.1016)
			(end 0.3048 0.9906)
			(stroke
				(width 0)
				(type default)
			)
			(fill no)
			(layer "F.CrtYd")
		)
		(fp_line
			(start 0.3048 0.9906)
			(end 0.3048 -0.1016)
			(stroke
				(width 0.1)
				(type default)
			)
			(layer "F.Fab")
		)
		(fp_line
			(start 0.3048 -0.1016)
			(end -0.3048 -0.1016)
			(stroke
				(width 0.1)
				(type default)
			)
			(layer "F.Fab")
		)
		(fp_line
			(start -0.3048 0.9906)
			(end 0.3048 0.9906)
			(stroke
				(width 0.1)
				(type default)
			)
			(layer "F.Fab")
		)
		(fp_line
			(start -0.3048 -0.1016)
			(end -0.3048 0.9906)
			(stroke
				(width 0.1)
				(type default)
			)
			(layer "F.Fab")
		)
		(pad "1" smd rect
			(at 0 0 180)
			(size 0.508 0.508)
			(layers "F.Cu" "F.Mask" "F.Paste")
			(net "FM_PVTT_GHJ_EN_R")
		)
		(pad "2" smd rect
			(at 0 0.889 180)
			(size 0.508 0.508)
			(layers "F.Cu" "F.Mask" "F.Paste")
			(net "GND")
		)
		(zone
			(layer "F.Cu")
			(hatch none 0.5)
			(connect_pads
				(clearance 0)
			)
			(min_thickness 0.25)
			(keepout
				(tracks not_allowed)
				(vias allowed)
				(pads allowed)
				(copperpour not_allowed)
				(footprints allowed)
			)
			(placement
				(enabled no)
				(sheetname "")
			)
			(fill
				(thermal_gap 0.5)
				(thermal_bridge_width 0.5)
				(island_removal_mode 0)
			)
			(polygon
				(pts
					(xy 167.5638 -6.7564) (xy 167.5638 -7.1374) (xy 167.0558 -7.1374) (xy 167.0558 -6.7564)
				)
			)
		)
		(zone
			(layer "F.Cu")
			(hatch none 0.5)
			(connect_pads
				(clearance 0)
			)
			(min_thickness 0.25)
			(keepout
				(tracks allowed)
				(vias not_allowed)
				(pads allowed)
				(copperpour not_allowed)
				(footprints allowed)
			)
			(placement
				(enabled no)
				(sheetname "")
			)
			(fill
				(thermal_gap 0.5)
				(thermal_bridge_width 0.5)
				(island_removal_mode 0)
			)
			(polygon
				(pts
					(xy 167.5638 -6.7564) (xy 167.5638 -7.1374) (xy 167.0558 -7.1374) (xy 167.0558 -6.7564)
				)
			)
		)
	)
)
